# T6G (Grand Teton) — schematic netlist excerpt (pin names and nets, part order shuffled) for the footprints in the layout excerpt that follows; sources: Cadence DE-HDL packaged netlist, KiCad conversion of 04192023_DAF0TMB3IC0_F0TG_MB_C_brd_V02_OCP.brd

C859  Q_CAP_DIFFBUS  DIFF BUS_0.22UF 6.3V 20% X6S  pkg C0201  page 64 : \1\ = P5E_CPU0_P2_TX_C_DP<5> ; \2\ = P5E_CPU0_P2_TX_DP<5>
R3836  Q_RES  10K 1% CHIP  pkg 0402LF  page 152 : A = P3V3_AUX ; B = HP_LVC3_SCM_HSC_PWRGD_R
L8  Q_INDUCTOR  100NH/16A IND  pkg SMLF  page 345 : \1\ = P0V9_CPU1_RT_2D ; \2\ = P0V9_CPU1_RT2_2A

(kicad_pcb
	(version 20260206)
	(generator "pcbnew")
	(generator_version "10.0")
	(general
		(thickness 1.6)
		(legacy_teardrops no)
	)
	(paper "A4")
	(title_block
		(title "04192023_DAF0TMB3IC0_F0TG_MB_C_brd_V02_OCP.brd")
		(comment 1 "Grand Teton / footprints 93-95 of 8354")
	)
	(layers
		(0 "F.Cu" signal "TOP")
		(4 "In1.Cu" signal "GND")
		(6 "In2.Cu" signal "IN1")
		(8 "In3.Cu" signal "GND1")
		(10 "In4.Cu" signal "IN2")
		(12 "In5.Cu" signal "GND2")
		(14 "In6.Cu" signal "IN3")
		(16 "In7.Cu" signal "GND3")
		(18 "In8.Cu" signal "VCC")
		(20 "In9.Cu" signal "VCC1")
		(22 "In10.Cu" signal "GND4")
		(24 "In11.Cu" signal "IN4")
		(26 "In12.Cu" signal "GND5")
		(28 "In13.Cu" signal "IN5")
		(30 "In14.Cu" signal "GND6")
		(32 "In15.Cu" signal "IN6")
		(34 "In16.Cu" signal "GND7")
		(2 "B.Cu" signal "BOTTOM")
		(9 "F.Adhes" user "F.Adhesive")
		(11 "B.Adhes" user "B.Adhesive")
		(13 "F.Paste" user "Package Geometry/Pastemask Top")
		(15 "B.Paste" user "Package Geometry/Pastemask Bottom")
		(5 "F.SilkS" user "Ref Des/Silkscreen Top")
		(7 "B.SilkS" user "Ref Des/Silkscreen Bottom")
		(1 "F.Mask" user "Board Geometry/Soldermask Top")
		(3 "B.Mask" user "Board Geometry/Soldermask Bottom")
		(17 "Dwgs.User" user "User.Drawings")
		(19 "Cmts.User" user "User.Comments")
		(21 "Eco1.User" user "User.Eco1")
		(23 "Eco2.User" user "User.Eco2")
		(25 "Edge.Cuts" user "Board Geometry/Outline")
		(27 "Margin" user)
		(31 "F.CrtYd" user "Package Geometry/Place Bound Top")
		(29 "B.CrtYd" user "Package Geometry/Place Bound Bottom")
		(35 "F.Fab" user "Ref Des/Assembly Top")
		(33 "B.Fab" user "Ref Des/Assembly Bottom")
	)
	(footprint ""
		(layer "F.Cu")
		(at 173.216062 -29.430472)
		(property "Reference" "R3836"
			(at 0 0 0)
			(layer "F.SilkS")
			(hide yes)
			(effects
				(font
					(size 1.27 1.27)
				)
			)
		)
		(property "Value" ""
			(at 0 0 0)
			(layer "F.Fab")
			(effects
				(font
					(size 1.27 1.27)
				)
			)
		)
		(duplicate_pad_numbers_are_jumpers no)
		(fp_line
			(start -0.7874 -0.4064)
			(end 0.7874 -0.4064)
			(stroke
				(width 0.1524)
				(type default)
			)
			(layer "F.SilkS")
		)
		(fp_line
			(start -0.7874 0.4064)
			(end -0.7874 -0.4064)
			(stroke
				(width 0.1524)
				(type default)
			)
			(layer "F.SilkS")
		)
		(fp_line
			(start 0.7874 -0.4064)
			(end 0.7874 0.4064)
			(stroke
				(width 0.1524)
				(type default)
			)
			(layer "F.SilkS")
		)
		(fp_line
			(start 0.7874 0.4064)
			(end -0.7874 0.4064)
			(stroke
				(width 0.1524)
				(type default)
			)
			(layer "F.SilkS")
		)
		(fp_line
			(start -0.67945 -0.305054)
			(end -0.12065 -0.305054)
			(stroke
				(width 0.1)
				(type default)
			)
			(layer "F.Fab")
		)
		(fp_line
			(start -0.67945 0.3048)
			(end -0.67945 -0.305054)
			(stroke
				(width 0.1)
				(type default)
			)
			(layer "F.Fab")
		)
		(fp_line
			(start -0.12065 -0.305054)
			(end -0.12065 -0.2794)
			(stroke
				(width 0.1)
				(type default)
			)
			(layer "F.Fab")
		)
		(fp_line
			(start -0.12065 -0.2794)
			(end 0.12065 -0.2794)
			(stroke
				(width 0.1)
				(type default)
			)
			(layer "F.Fab")
		)
		(fp_line
			(start -0.12065 0.2794)
			(end -0.12065 0.3048)
			(stroke
				(width 0.1)
				(type default)
			)
			(layer "F.Fab")
		)
		(fp_line
			(start -0.12065 0.3048)
			(end -0.67945 0.3048)
			(stroke
				(width 0.1)
				(type default)
			)
			(layer "F.Fab")
		)
		(fp_line
			(start 0.120396 0.2794)
			(end -0.12065 0.2794)
			(stroke
				(width 0.1)
				(type default)
			)
			(layer "F.Fab")
		)
		(fp_line
			(start 0.120396 0.3048)
			(end 0.120396 0.2794)
			(stroke
				(width 0.1)
				(type default)
			)
			(layer "F.Fab")
		)
		(fp_line
			(start 0.12065 -0.3048)
			(end 0.67945 -0.3048)
			(stroke
				(width 0.1)
				(type default)
			)
			(layer "F.Fab")
		)
		(fp_line
			(start 0.12065 -0.2794)
			(end 0.12065 -0.3048)
			(stroke
				(width 0.1)
				(type default)
			)
			(layer "F.Fab")
		)
		(fp_line
			(start 0.67945 -0.3048)
			(end 0.67945 0.3048)
			(stroke
				(width 0.1)
				(type default)
			)
			(layer "F.Fab")
		)
		(fp_line
			(start 0.67945 0.3048)
			(end 0.120396 0.3048)
			(stroke
				(width 0.1)
				(type default)
			)
			(layer "F.Fab")
		)
		(pad "1" smd circle
			(at -0.40005 0)
			(size 0 0)
			(layers "F.Cu" "F.Mask" "F.Paste")
			(net "P3V3_AUX")
		)
		(pad "2" smd circle
			(at 0.40005 0)
			(size 0 0)
			(layers "F.Cu" "F.Mask" "F.Paste")
			(net "HP_LVC3_SCM_HSC_PWRGD_R")
		)
	)
	(footprint ""
		(layer "F.Cu")
		(at 405.42464 -381.41783 -90)
		(property "Reference" "C859"
			(at 0 0 270)
			(layer "F.SilkS")
			(hide yes)
			(effects
				(font
					(size 1.27 1.27)
				)
			)
		)
		(property "Value" ""
			(at 0 0 270)
			(layer "F.Fab")
			(effects
				(font
					(size 1.27 1.27)
				)
			)
		)
		(duplicate_pad_numbers_are_jumpers no)
		(fp_line
			(start -0.299974 0.150114)
			(end -0.299974 -0.150114)
			(stroke
				(width 0.1)
				(type default)
			)
			(layer "F.Fab")
		)
		(fp_line
			(start 0.299974 0.150114)
			(end -0.299974 0.150114)
			(stroke
				(width 0.1)
				(type default)
			)
			(layer "F.Fab")
		)
		(fp_line
			(start -0.299974 -0.150114)
			(end 0.299974 -0.150114)
			(stroke
				(width 0.1)
				(type default)
			)
			(layer "F.Fab")
		)
		(fp_line
			(start 0.299974 -0.150114)
			(end 0.299974 0.150114)
			(stroke
				(width 0.1)
				(type default)
			)
			(layer "F.Fab")
		)
		(pad "1" smd rect
			(at -0.2667 0 270)
			(size 0.3048 0.381)
			(layers "F.Cu" "F.Mask" "F.Paste")
			(net "P5E_CPU0_P2_TX_C_DP<5>")
		)
		(pad "2" smd rect
			(at 0.2667 0 270)
			(size 0.3048 0.381)
			(layers "F.Cu" "F.Mask" "F.Paste")
			(net "P5E_CPU0_P2_TX_DP<5>")
		)
	)
	(footprint ""
		(layer "F.Cu")
		(at 140.250672 -392.521694)
		(property "Reference" "L8"
			(at -2.3876 -2.969768 0)
			(unlocked yes)
			(layer "F.SilkS")
			(effects
				(font
					(size 0.7874 0.5842)
					(thickness 0.1524)
				)
				(justify left)
			)
		)
		(property "Value" ""
			(at 0 0 0)
			(layer "F.Fab")
			(effects
				(font
					(size 1.27 1.27)
				)
			)
		)
		(duplicate_pad_numbers_are_jumpers no)
		(fp_line
			(start -2.249932 -2.249932)
			(end 2.249932 -2.249932)
			(stroke
				(width 0.1524)
				(type default)
			)
			(layer "F.SilkS")
		)
		(fp_line
			(start -2.249932 -1.3843)
			(end -2.249932 -2.249932)
			(stroke
				(width 0.1524)
				(type default)
			)
			(layer "F.SilkS")
		)
		(fp_line
			(start -2.249932 2.249932)
			(end -2.249932 1.3843)
			(stroke
				(width 0.1524)
				(type default)
			)
			(layer "F.SilkS")
		)
		(fp_line
			(start 2.249932 -2.249932)
			(end 2.249932 -1.3843)
			(stroke
				(width 0.1524)
				(type default)
			)
			(layer "F.SilkS")
		)
		(fp_line
			(start 2.249932 1.3843)
			(end 2.249932 2.249932)
			(stroke
				(width 0.1524)
				(type default)
			)
			(layer "F.SilkS")
		)
		(fp_line
			(start 2.249932 2.249932)
			(end -2.249932 2.249932)
			(stroke
				(width 0.1524)
				(type default)
			)
			(layer "F.SilkS")
		)
		(fp_line
			(start -2.249932 -2.249932)
			(end 2.249932 -2.249932)
			(stroke
				(width 0.1)
				(type default)
			)
			(layer "F.Fab")
		)
		(fp_line
			(start -2.249932 2.249932)
			(end -2.249932 -2.249932)
			(stroke
				(width 0.1)
				(type default)
			)
			(layer "F.Fab")
		)
		(fp_line
			(start 2.249932 -2.249932)
			(end 2.249932 2.249932)
			(stroke
				(width 0.1)
				(type default)
			)
			(layer "F.Fab")
		)
		(fp_line
			(start 2.249932 2.249932)
			(end -2.249932 2.249932)
			(stroke
				(width 0.1)
				(type default)
			)
			(layer "F.Fab")
		)
		(pad "1" smd rect
			(at -1.82499 0)
			(size 1.0668 2.5146)
			(layers "F.Cu" "F.Mask" "F.Paste")
			(net "P0V9_CPU1_RT_2D")
		)
		(pad "2" smd rect
			(at 1.82499 0)
			(size 1.0668 2.5146)
			(layers "F.Cu" "F.Mask" "F.Paste")
			(net "P0V9_CPU1_RT2_2A")
		)
	)
)
